(kicad_pcb
	(version 20241229)
	(generator "pcbnew")
	(generator_version "9.0")
	(general
		(thickness 1.62)
		(legacy_teardrops no)
	)
	(paper "A3")
	(title_block
		(title "COM Express 7 Baseboard")
		(date "2025-02-04")
		(rev "1.1.2")
		(company "Antmicro Ltd")
		(comment 1 "www.antmicro.com")
		(comment 9 "footprints 132-136 of 802")
	)
	(layers
		(0 "F.Cu" signal)
		(4 "In1.Cu" signal)
		(6 "In2.Cu" signal)
		(8 "In3.Cu" signal)
		(10 "In4.Cu" signal)
		(12 "In5.Cu" signal)
		(14 "In6.Cu" signal)
		(2 "B.Cu" signal)
		(9 "F.Adhes" user "F.Adhesive")
		(11 "B.Adhes" user "B.Adhesive")
		(13 "F.Paste" user)
		(15 "B.Paste" user)
		(5 "F.SilkS" user "F.Silkscreen")
		(7 "B.SilkS" user "B.Silkscreen")
		(1 "F.Mask" user)
		(3 "B.Mask" user)
		(17 "Dwgs.User" user "User.Drawings")
		(19 "Cmts.User" user "User.Comments")
		(21 "Eco1.User" user "User.Eco1")
		(23 "Eco2.User" user "User.Eco2")
		(25 "Edge.Cuts" user)
		(27 "Margin" user)
		(31 "F.CrtYd" user "F.Courtyard")
		(29 "B.CrtYd" user "B.Courtyard")
		(35 "F.Fab" user)
		(33 "B.Fab" user)
	)
	(footprint "antmicro-footprints:R_0402_1005Metric"
		(layer "F.Cu")
		(at 312.765499 97.4365 -90)
		(descr "Resistor SMD 0402")
		(tags "resistor SMD 0402")
		(property "Reference" "R107"
			(at -10.1265 -4.734501 90)
			(layer "F.SilkS")
			(effects
				(font
					(size 0.7 0.7)
					(thickness 0.15)
				)
				(justify right bottom)
			)
		)
		(property "Value" "R_15k_0402"
			(at -1.011843 1.772047 90)
			(layer "F.Fab")
			(effects
				(font
					(size 0.7 0.7)
					(thickness 0.15)
				)
				(justify right bottom)
			)
		)
		(property "Datasheet" "https://www.bourns.com/docs/product-datasheets/cr.pdf"
			(at 0 0 270)
			(layer "F.Fab")
			(hide yes)
			(effects
				(font
					(size 1.27 1.27)
					(thickness 0.15)
				)
			)
		)
		(property "Author" "Antmicro"
			(at 215.328999 410.201999 0)
			(layer "F.Fab")
			(hide yes)
			(effects
				(font
					(size 1 1)
					(thickness 0.15)
				)
			)
		)
		(property "License" "Apache-2.0"
			(at 215.328999 410.201999 0)
			(layer "F.Fab")
			(hide yes)
			(effects
				(font
					(size 1 1)
					(thickness 0.15)
				)
			)
		)
		(property "MPN" "CR0402-FX-1502GLF"
			(at 215.328999 410.201999 0)
			(layer "F.Fab")
			(hide yes)
			(effects
				(font
					(size 1 1)
					(thickness 0.15)
				)
			)
		)
		(property "Manufacturer" "Bourns"
			(at 215.328999 410.201999 0)
			(layer "F.Fab")
			(hide yes)
			(effects
				(font
					(size 1 1)
					(thickness 0.15)
				)
			)
		)
		(property "Public" "False"
			(at 215.328999 410.201999 0)
			(layer "F.Fab")
			(hide yes)
			(effects
				(font
					(size 1 1)
					(thickness 0.15)
				)
			)
		)
		(property "Tolerance" "1%"
			(at 215.328999 410.201999 0)
			(layer "F.Fab")
			(hide yes)
			(effects
				(font
					(size 1 1)
					(thickness 0.15)
				)
			)
		)
		(property "Val" "15k"
			(at 215.328999 410.201999 0)
			(layer "F.Fab")
			(hide yes)
			(effects
				(font
					(size 1 1)
					(thickness 0.15)
				)
			)
		)
		(sheetname "Power")
		(sheetfile "power.kicad_sch")
		(attr smd)
		(fp_rect
			(start -0.925 -0.47)
			(end 0.925 0.47)
			(stroke
				(width 0.05)
				(type default)
			)
			(fill no)
			(layer "F.CrtYd")
		)
		(fp_rect
			(start -0.5 -0.25)
			(end 0.5 0.25)
			(stroke
				(width 0.15)
				(type solid)
			)
			(fill no)
			(layer "F.Fab")
		)
		(pad "1" smd roundrect
			(at -0.48 0 270)
			(size 0.59 0.64)
			(layers "F.Cu" "F.Mask" "F.Paste")
			(roundrect_rratio 0.25)
			(net 584 "Net-(U21-EN)")
			(pintype "passive")
			(teardrops
				(best_length_ratio 0.2)
				(max_length 1)
				(best_width_ratio 0.9)
				(max_width 2)
				(curved_edges yes)
				(filter_ratio 0.9)
				(enabled yes)
				(allow_two_segments yes)
				(prefer_zone_connections yes)
			)
		)
		(pad "2" smd roundrect
			(at 0.48 0 270)
			(size 0.59 0.64)
			(layers "F.Cu" "F.Mask" "F.Paste")
			(roundrect_rratio 0.25)
			(net 62 "+12V_AON")
			(pintype "passive")
			(teardrops
				(best_length_ratio 0.2)
				(max_length 1)
				(best_width_ratio 0.9)
				(max_width 2)
				(curved_edges yes)
				(filter_ratio 0.9)
				(enabled yes)
				(allow_two_segments yes)
				(prefer_zone_connections yes)
			)
		)
	)
	(footprint "antmicro-footprints:R_0402_1005Metric"
		(layer "F.Cu")
		(at 113.4 150.36 -90)
		(descr "Resistor SMD 0402")
		(tags "resistor SMD 0402")
		(property "Reference" "R209"
			(at -0.46 -4.5 90)
			(layer "F.SilkS")
			(effects
				(font
					(size 0.7 0.7)
					(thickness 0.15)
				)
				(justify right bottom)
			)
		)
		(property "Value" "R_1k_0402"
			(at -1.011843 1.772047 90)
			(layer "F.Fab")
			(effects
				(font
					(size 0.7 0.7)
					(thickness 0.15)
				)
				(justify right bottom)
			)
		)
		(property "Datasheet" "https://www.bourns.com/docs/product-datasheets/cr.pdf"
			(at 0 0 270)
			(layer "F.Fab")
			(hide yes)
			(effects
				(font
					(size 1.27 1.27)
					(thickness 0.15)
				)
			)
		)
		(property "Author" "Antmicro"
			(at -36.96 263.76 0)
			(layer "F.Fab")
			(hide yes)
			(effects
				(font
					(size 1 1)
					(thickness 0.15)
				)
			)
		)
		(property "License" "Apache-2.0"
			(at -36.96 263.76 0)
			(layer "F.Fab")
			(hide yes)
			(effects
				(font
					(size 1 1)
					(thickness 0.15)
				)
			)
		)
		(property "MPN" "CR0402-FX-1001GLF"
			(at -36.96 263.76 0)
			(layer "F.Fab")
			(hide yes)
			(effects
				(font
					(size 1 1)
					(thickness 0.15)
				)
			)
		)
		(property "Manufacturer" "Bourns"
			(at -36.96 263.76 0)
			(layer "F.Fab")
			(hide yes)
			(effects
				(font
					(size 1 1)
					(thickness 0.15)
				)
			)
		)
		(property "Public" "False"
			(at -36.96 263.76 0)
			(layer "F.Fab")
			(hide yes)
			(effects
				(font
					(size 1 1)
					(thickness 0.15)
				)
			)
		)
		(property "Tolerance" "1%"
			(at -36.96 263.76 0)
			(layer "F.Fab")
			(hide yes)
			(effects
				(font
					(size 1 1)
					(thickness 0.15)
				)
			)
		)
		(property "Val" "1k"
			(at -36.96 263.76 0)
			(layer "F.Fab")
			(hide yes)
			(effects
				(font
					(size 1 1)
					(thickness 0.15)
				)
			)
		)
		(sheetname "PCIe redriver")
		(sheetfile "pcie_redriver.kicad_sch")
		(attr smd)
		(fp_rect
			(start -0.925 -0.47)
			(end 0.925 0.47)
			(stroke
				(width 0.05)
				(type default)
			)
			(fill no)
			(layer "F.CrtYd")
		)
		(fp_rect
			(start -0.5 -0.25)
			(end 0.5 0.25)
			(stroke
				(width 0.15)
				(type solid)
			)
			(fill no)
			(layer "F.Fab")
		)
		(pad "1" smd roundrect
			(at -0.48 0 270)
			(size 0.59 0.64)
			(layers "F.Cu" "F.Mask" "F.Paste")
			(roundrect_rratio 0.25)
			(net 1 "GND")
			(pintype "passive")
			(teardrops
				(best_length_ratio 0.2)
				(max_length 1)
				(best_width_ratio 0.9)
				(max_width 2)
				(curved_edges yes)
				(filter_ratio 0.9)
				(enabled yes)
				(allow_two_segments yes)
				(prefer_zone_connections yes)
			)
		)
		(pad "2" smd roundrect
			(at 0.48 0 270)
			(size 0.59 0.64)
			(layers "F.Cu" "F.Mask" "F.Paste")
			(roundrect_rratio 0.25)
			(net 626 "/PCIe redriver/TX_FG0")
			(pintype "passive")
			(teardrops
				(best_length_ratio 0.2)
				(max_length 1)
				(best_width_ratio 0.9)
				(max_width 2)
				(curved_edges yes)
				(filter_ratio 0.9)
				(enabled yes)
				(allow_two_segments yes)
				(prefer_zone_connections yes)
			)
		)
	)
	(footprint "antmicro-footprints:SOD-123FL"
		(layer "F.Cu")
		(at 308.5 149.11 -90)
		(property "Reference" "D24"
			(at -2.5 -0.8 180)
			(layer "F.SilkS")
			(effects
				(font
					(size 0.7 0.7)
					(thickness 0.15)
				)
				(justify right bottom)
			)
		)
		(property "Value" "SMF4L15A"
			(at 0 1.967 90)
			(layer "F.Fab")
			(effects
				(font
					(size 0.7 0.7)
					(thickness 0.15)
				)
				(justify right bottom)
			)
		)
		(property "Datasheet" "https://www.littelfuse.com/media?resourcetype=datasheets&itemid=d2ba8fab-1de3-4176-8530-f36ecb0b8799&filename=smf4l"
			(at 0 0 270)
			(layer "F.Fab")
			(hide yes)
			(effects
				(font
					(size 1.27 1.27)
					(thickness 0.15)
				)
			)
		)
		(property "Author" "Antmicro"
			(at 159.39 457.61 0)
			(layer "F.Fab")
			(hide yes)
			(effects
				(font
					(size 1 1)
					(thickness 0.15)
				)
			)
		)
		(property "License" "Apache-2.0"
			(at 159.39 457.61 0)
			(layer "F.Fab")
			(hide yes)
			(effects
				(font
					(size 1 1)
					(thickness 0.15)
				)
			)
		)
		(property "MPN" "SMF4L15A"
			(at 159.39 457.61 0)
			(layer "F.Fab")
			(hide yes)
			(effects
				(font
					(size 1 1)
					(thickness 0.15)
				)
			)
		)
		(property "Manufacturer" "Littelfuse"
			(at 159.39 457.61 0)
			(layer "F.Fab")
			(hide yes)
			(effects
				(font
					(size 1 1)
					(thickness 0.15)
				)
			)
		)
		(property "Public" "False"
			(at 159.39 457.61 0)
			(layer "F.Fab")
			(hide yes)
			(effects
				(font
					(size 1 1)
					(thickness 0.15)
				)
			)
		)
		(sheetname "Power")
		(sheetfile "power.kicad_sch")
		(attr smd)
		(fp_line
			(start -2.3 1.1)
			(end 0 1.1)
			(stroke
				(width 0.15)
				(type solid)
			)
			(layer "F.SilkS")
		)
		(fp_line
			(start -2.3 -1.1)
			(end -2.3 1.1)
			(stroke
				(width 0.15)
				(type solid)
			)
			(layer "F.SilkS")
		)
		(fp_line
			(start 0 -1.1)
			(end -2.3 -1.1)
			(stroke
				(width 0.15)
				(type solid)
			)
			(layer "F.SilkS")
		)
		(fp_rect
			(start -2.35 -1.125)
			(end 2.35 1.125)
			(stroke
				(width 0.05)
				(type solid)
			)
			(fill no)
			(layer "F.CrtYd")
		)
		(fp_rect
			(start -1.825 -0.875)
			(end 1.824 0.873)
			(stroke
				(width 0.15)
				(type solid)
			)
			(fill no)
			(layer "F.Fab")
		)
		(fp_rect
			(start -0.775 -0.875)
			(end -0.525 0.875)
			(stroke
				(width 0.15)
				(type solid)
			)
			(fill yes)
			(layer "F.Fab")
		)
		(pad "1" smd roundrect
			(at -1.43 0 270)
			(size 1.34 1.8)
			(layers "F.Cu" "F.Mask" "F.Paste")
			(roundrect_rratio 0.14)
			(net 145 "Net-(D24-C)")
			(pinfunction "C")
			(pintype "passive")
			(teardrops
				(best_length_ratio 0.2)
				(max_length 1)
				(best_width_ratio 0.9)
				(max_width 2)
				(curved_edges yes)
				(filter_ratio 0.9)
				(enabled yes)
				(allow_two_segments yes)
				(prefer_zone_connections yes)
			)
		)
		(pad "2" smd roundrect
			(at 1.429 0 270)
			(size 1.34 1.8)
			(layers "F.Cu" "F.Mask" "F.Paste")
			(roundrect_rratio 0.14)
			(net 1 "GND")
			(pinfunction "A")
			(pintype "passive")
			(teardrops
				(best_length_ratio 0.2)
				(max_length 1)
				(best_width_ratio 0.9)
				(max_width 2)
				(curved_edges yes)
				(filter_ratio 0.9)
				(enabled yes)
				(allow_two_segments yes)
				(prefer_zone_connections yes)
			)
		)
	)
	(footprint "antmicro-footprints:C_0402_1005Metric"
		(layer "F.Cu")
		(at 304.85 146.61 180)
		(descr "Capacitor SMD 0402")
		(tags "capacitor SMD 0402")
		(property "Reference" "C203"
			(at -1.35 0.5 0)
			(layer "F.SilkS")
			(effects
				(font
					(size 0.7 0.7)
					(thickness 0.15)
				)
				(justify right bottom)
			)
		)
		(property "Value" "C_100n_0402"
			(at -1.022927 2.155213 0)
			(layer "F.Fab")
			(effects
				(font
					(size 0.7 0.7)
					(thickness 0.15)
				)
				(justify right bottom)
			)
		)
		(property "Datasheet" "https://www.murata.com/products/productdetail?partno=GRM155R61H104KE14%23"
			(at 0 0 180)
			(layer "F.Fab")
			(hide yes)
			(effects
				(font
					(size 1.27 1.27)
					(thickness 0.15)
				)
			)
		)
		(property "Author" "Antmicro"
			(at 609.7 293.22 0)
			(layer "F.Fab")
			(hide yes)
			(effects
				(font
					(size 1 1)
					(thickness 0.15)
				)
			)
		)
		(property "Dielectric" "X5R"
			(at 609.7 293.22 0)
			(layer "F.Fab")
			(hide yes)
			(effects
				(font
					(size 1 1)
					(thickness 0.15)
				)
			)
		)
		(property "License" "Apache-2.0"
			(at 609.7 293.22 0)
			(layer "F.Fab")
			(hide yes)
			(effects
				(font
					(size 1 1)
					(thickness 0.15)
				)
			)
		)
		(property "MPN" "GRM155R61H104KE14D"
			(at 609.7 293.22 0)
			(layer "F.Fab")
			(hide yes)
			(effects
				(font
					(size 1 1)
					(thickness 0.15)
				)
			)
		)
		(property "Manufacturer" "Murata"
			(at 609.7 293.22 0)
			(layer "F.Fab")
			(hide yes)
			(effects
				(font
					(size 1 1)
					(thickness 0.15)
				)
			)
		)
		(property "Public" "False"
			(at 609.7 293.22 0)
			(layer "F.Fab")
			(hide yes)
			(effects
				(font
					(size 1 1)
					(thickness 0.15)
				)
			)
		)
		(property "Val" "100n"
			(at 609.7 293.22 0)
			(layer "F.Fab")
			(hide yes)
			(effects
				(font
					(size 1 1)
					(thickness 0.15)
				)
			)
		)
		(property "Voltage" "50V"
			(at 609.7 293.22 0)
			(layer "F.Fab")
			(hide yes)
			(effects
				(font
					(size 1 1)
					(thickness 0.15)
				)
			)
		)
		(sheetname "Power")
		(sheetfile "power.kicad_sch")
		(attr smd)
		(fp_rect
			(start -0.925 -0.47)
			(end 0.925 0.47)
			(stroke
				(width 0.05)
				(type default)
			)
			(fill no)
			(layer "F.CrtYd")
		)
		(fp_line
			(start 0.504 0.248)
			(end -0.494 0.248)
			(stroke
				(width 0.15)
				(type solid)
			)
			(layer "F.Fab")
		)
		(fp_line
			(start 0.504 -0.25)
			(end 0.504 0.248)
			(stroke
				(width 0.15)
				(type solid)
			)
			(layer "F.Fab")
		)
		(fp_line
			(start -0.494 0.248)
			(end -0.494 -0.25)
			(stroke
				(width 0.15)
				(type solid)
			)
			(layer "F.Fab")
		)
		(fp_line
			(start -0.494 -0.25)
			(end 0.504 -0.25)
			(stroke
				(width 0.15)
				(type solid)
			)
			(layer "F.Fab")
		)
		(pad "1" smd roundrect
			(at -0.48 0 180)
			(size 0.59 0.64)
			(layers "F.Cu" "F.Mask" "F.Paste")
			(roundrect_rratio 0.25)
			(net 1 "GND")
			(pintype "passive")
			(teardrops
				(best_length_ratio 0.2)
				(max_length 1)
				(best_width_ratio 0.9)
				(max_width 2)
				(curved_edges yes)
				(filter_ratio 0.9)
				(enabled yes)
				(allow_two_segments yes)
				(prefer_zone_connections yes)
			)
		)
		(pad "2" smd roundrect
			(at 0.48 0 180)
			(size 0.59 0.64)
			(layers "F.Cu" "F.Mask" "F.Paste")
			(roundrect_rratio 0.25)
			(net 73 "+3V3_AON")
			(pintype "passive")
			(teardrops
				(best_length_ratio 0.2)
				(max_length 1)
				(best_width_ratio 0.9)
				(max_width 2)
				(curved_edges yes)
				(filter_ratio 0.9)
				(enabled yes)
				(allow_two_segments yes)
				(prefer_zone_connections yes)
			)
		)
	)
	(footprint "antmicro-footprints:C_0603_1608Metric"
		(layer "F.Cu")
		(at 314.224999 103.15 -90)
		(descr "Capacitor SMD 0603")
		(tags "capacitor 0603")
		(property "Reference" "C40"
			(at -3.34 -0.425001 90)
			(layer "F.SilkS")
			(effects
				(font
					(size 0.7 0.7)
					(thickness 0.15)
				)
				(justify right bottom)
			)
		)
		(property "Value" "C_22u_16V_0603"
			(at -1.42757 1.770288 90)
			(layer "F.Fab")
			(effects
				(font
					(size 0.7 0.7)
					(thickness 0.15)
				)
				(justify right bottom)
			)
		)
		(property "Datasheet" "https://product.samsungsem.com/mlcc/CL10A226MO7JZN.do"
			(at 0 0 270)
			(layer "F.Fab")
			(hide yes)
			(effects
				(font
					(size 1.27 1.27)
					(thickness 0.15)
				)
			)
		)
		(property "Author" "Antmicro"
			(at 211.074999 417.374999 0)
			(layer "F.Fab")
			(hide yes)
			(effects
				(font
					(size 1 1)
					(thickness 0.15)
				)
			)
		)
		(property "Dielectric" ""
			(at 211.074999 417.374999 0)
			(layer "F.Fab")
			(hide yes)
			(effects
				(font
					(size 1 1)
					(thickness 0.15)
				)
			)
		)
		(property "License" "Apache-2.0"
			(at 211.074999 417.374999 0)
			(layer "F.Fab")
			(hide yes)
			(effects
				(font
					(size 1 1)
					(thickness 0.15)
				)
			)
		)
		(property "MPN" "CL10A226MO7JZNC"
			(at 211.074999 417.374999 0)
			(layer "F.Fab")
			(hide yes)
			(effects
				(font
					(size 1 1)
					(thickness 0.15)
				)
			)
		)
		(property "Manufacturer" "Samsung Electro-Mechanics"
			(at 211.074999 417.374999 0)
			(layer "F.Fab")
			(hide yes)
			(effects
				(font
					(size 1 1)
					(thickness 0.15)
				)
			)
		)
		(property "Public" "False"
			(at 211.074999 417.374999 0)
			(layer "F.Fab")
			(hide yes)
			(effects
				(font
					(size 1 1)
					(thickness 0.15)
				)
			)
		)
		(property "Val" "22u"
			(at 211.074999 417.374999 0)
			(layer "F.Fab")
			(hide yes)
			(effects
				(font
					(size 1 1)
					(thickness 0.15)
				)
			)
		)
		(property "Voltage" "16V"
			(at 211.074999 417.374999 0)
			(layer "F.Fab")
			(hide yes)
			(effects
				(font
					(size 1 1)
					(thickness 0.15)
				)
			)
		)
		(sheetname "Power")
		(sheetfile "power.kicad_sch")
		(attr smd)
		(fp_line
			(start -0.15 0.4)
			(end 0.15 0.4)
			(stroke
				(width 0.15)
				(type solid)
			)
			(layer "F.SilkS")
		)
		(fp_line
			(start -0.15 -0.4)
			(end 0.15 -0.4)
			(stroke
				(width 0.15)
				(type solid)
			)
			(layer "F.SilkS")
		)
		(fp_rect
			(start -1.25 -0.65)
			(end 1.25 0.65)
			(stroke
				(width 0.05)
				(type solid)
			)
			(fill no)
			(layer "F.CrtYd")
		)
		(fp_rect
			(start -0.8 -0.4)
			(end 0.8 0.4)
			(stroke
				(width 0.15)
				(type solid)
			)
			(fill no)
			(layer "F.Fab")
		)
		(pad "1" smd roundrect
			(at -0.7 0 270)
			(size 0.8 1)
			(layers "F.Cu" "F.Mask" "F.Paste")
			(roundrect_rratio 0.2)
			(net 1 "GND")
			(pintype "passive")
			(teardrops
				(best_length_ratio 0.2)
				(max_length 1)
				(best_width_ratio 0.9)
				(max_width 2)
				(curved_edges yes)
				(filter_ratio 0.9)
				(enabled yes)
				(allow_two_segments yes)
				(prefer_zone_connections yes)
			)
		)
		(pad "2" smd roundrect
			(at 0.7 0 270)
			(size 0.8 1)
			(layers "F.Cu" "F.Mask" "F.Paste")
			(roundrect_rratio 0.2)
			(net 62 "+12V_AON")
			(pintype "passive")
			(teardrops
				(best_length_ratio 0.2)
				(max_length 1)
				(best_width_ratio 0.9)
				(max_width 2)
				(curved_edges yes)
				(filter_ratio 0.9)
				(enabled yes)
				(allow_two_segments yes)
				(prefer_zone_connections yes)
			)
		)
	)
)
